# T6G (Grand Teton) — schematic netlist excerpt (pin names and nets, part order shuffled) for the footprints in the layout excerpt that follows; sources: Cadence DE-HDL packaged netlist, KiCad conversion of 04192023_DAF0TMB3IC0_F0TG_MB_C_brd_V02_OCP.brd

R3336  Q_RES  0 5% CHIP  pkg 0402LF  page 233 : A = CLK_100M_BMC_RC_DN_R ; B = CLK_100M_BMC_RC_DN
R1740  Q_RES  22 1% CHIP  pkg 0402LF  page 171 : A = JTAG_SCM_PLD_R_TCK ; B = JTAG_SCM_PLD_TCK

(kicad_pcb
	(version 20260206)
	(generator "pcbnew")
	(generator_version "10.0")
	(general
		(thickness 1.6)
		(legacy_teardrops no)
	)
	(paper "A4")
	(title_block
		(title "04192023_DAF0TMB3IC0_F0TG_MB_C_brd_V02_OCP.brd")
		(comment 1 "Grand Teton / footprints 927-928 of 8354")
	)
	(layers
		(0 "F.Cu" signal "TOP")
		(4 "In1.Cu" signal "GND")
		(6 "In2.Cu" signal "IN1")
		(8 "In3.Cu" signal "GND1")
		(10 "In4.Cu" signal "IN2")
		(12 "In5.Cu" signal "GND2")
		(14 "In6.Cu" signal "IN3")
		(16 "In7.Cu" signal "GND3")
		(18 "In8.Cu" signal "VCC")
		(20 "In9.Cu" signal "VCC1")
		(22 "In10.Cu" signal "GND4")
		(24 "In11.Cu" signal "IN4")
		(26 "In12.Cu" signal "GND5")
		(28 "In13.Cu" signal "IN5")
		(30 "In14.Cu" signal "GND6")
		(32 "In15.Cu" signal "IN6")
		(34 "In16.Cu" signal "GND7")
		(2 "B.Cu" signal "BOTTOM")
		(9 "F.Adhes" user "F.Adhesive")
		(11 "B.Adhes" user "B.Adhesive")
		(13 "F.Paste" user "Package Geometry/Pastemask Top")
		(15 "B.Paste" user "Package Geometry/Pastemask Bottom")
		(5 "F.SilkS" user "Ref Des/Silkscreen Top")
		(7 "B.SilkS" user "Ref Des/Silkscreen Bottom")
		(1 "F.Mask" user "Board Geometry/Soldermask Top")
		(3 "B.Mask" user "Board Geometry/Soldermask Bottom")
		(17 "Dwgs.User" user "User.Drawings")
		(19 "Cmts.User" user "User.Comments")
		(21 "Eco1.User" user "User.Eco1")
		(23 "Eco2.User" user "User.Eco2")
		(25 "Edge.Cuts" user "Board Geometry/Outline")
		(27 "Margin" user)
		(31 "F.CrtYd" user "Package Geometry/Place Bound Top")
		(29 "B.CrtYd" user "Package Geometry/Place Bound Bottom")
		(35 "F.Fab" user "Ref Des/Assembly Top")
		(33 "B.Fab" user "Ref Des/Assembly Bottom")
	)
	(footprint ""
		(layer "F.Cu")
		(at 18.702782 -133.480302)
		(property "Reference" "R3336"
			(at 0 0 0)
			(layer "F.SilkS")
			(hide yes)
			(effects
				(font
					(size 1.27 1.27)
				)
			)
		)
		(property "Value" ""
			(at 0 0 0)
			(layer "F.Fab")
			(effects
				(font
					(size 1.27 1.27)
				)
			)
		)
		(duplicate_pad_numbers_are_jumpers no)
		(fp_line
			(start -0.7874 -0.4064)
			(end 0.7874 -0.4064)
			(stroke
				(width 0.1524)
				(type default)
			)
			(layer "F.SilkS")
		)
		(fp_line
			(start -0.7874 0.4064)
			(end -0.7874 -0.4064)
			(stroke
				(width 0.1524)
				(type default)
			)
			(layer "F.SilkS")
		)
		(fp_line
			(start 0.7874 -0.4064)
			(end 0.7874 0.4064)
			(stroke
				(width 0.1524)
				(type default)
			)
			(layer "F.SilkS")
		)
		(fp_line
			(start 0.7874 0.4064)
			(end -0.7874 0.4064)
			(stroke
				(width 0.1524)
				(type default)
			)
			(layer "F.SilkS")
		)
		(fp_line
			(start -0.67945 -0.305054)
			(end -0.12065 -0.305054)
			(stroke
				(width 0.1)
				(type default)
			)
			(layer "F.Fab")
		)
		(fp_line
			(start -0.67945 0.3048)
			(end -0.67945 -0.305054)
			(stroke
				(width 0.1)
				(type default)
			)
			(layer "F.Fab")
		)
		(fp_line
			(start -0.12065 -0.305054)
			(end -0.12065 -0.2794)
			(stroke
				(width 0.1)
				(type default)
			)
			(layer "F.Fab")
		)
		(fp_line
			(start -0.12065 -0.2794)
			(end 0.12065 -0.2794)
			(stroke
				(width 0.1)
				(type default)
			)
			(layer "F.Fab")
		)
		(fp_line
			(start -0.12065 0.2794)
			(end -0.12065 0.3048)
			(stroke
				(width 0.1)
				(type default)
			)
			(layer "F.Fab")
		)
		(fp_line
			(start -0.12065 0.3048)
			(end -0.67945 0.3048)
			(stroke
				(width 0.1)
				(type default)
			)
			(layer "F.Fab")
		)
		(fp_line
			(start 0.120396 0.2794)
			(end -0.12065 0.2794)
			(stroke
				(width 0.1)
				(type default)
			)
			(layer "F.Fab")
		)
		(fp_line
			(start 0.120396 0.3048)
			(end 0.120396 0.2794)
			(stroke
				(width 0.1)
				(type default)
			)
			(layer "F.Fab")
		)
		(fp_line
			(start 0.12065 -0.3048)
			(end 0.67945 -0.3048)
			(stroke
				(width 0.1)
				(type default)
			)
			(layer "F.Fab")
		)
		(fp_line
			(start 0.12065 -0.2794)
			(end 0.12065 -0.3048)
			(stroke
				(width 0.1)
				(type default)
			)
			(layer "F.Fab")
		)
		(fp_line
			(start 0.67945 -0.3048)
			(end 0.67945 0.3048)
			(stroke
				(width 0.1)
				(type default)
			)
			(layer "F.Fab")
		)
		(fp_line
			(start 0.67945 0.3048)
			(end 0.120396 0.3048)
			(stroke
				(width 0.1)
				(type default)
			)
			(layer "F.Fab")
		)
		(pad "1" smd circle
			(at -0.40005 0)
			(size 0 0)
			(layers "F.Cu" "F.Mask" "F.Paste")
			(net "CLK_100M_BMC_RC_DN_R")
		)
		(pad "2" smd circle
			(at 0.40005 0)
			(size 0 0)
			(layers "F.Cu" "F.Mask" "F.Paste")
			(net "CLK_100M_BMC_RC_DN")
		)
	)
	(footprint ""
		(layer "F.Cu")
		(at 118.718584 -57.852056)
		(property "Reference" "R1740"
			(at 0 0 0)
			(layer "F.SilkS")
			(hide yes)
			(effects
				(font
					(size 1.27 1.27)
				)
			)
		)
		(property "Value" ""
			(at 0 0 0)
			(layer "F.Fab")
			(effects
				(font
					(size 1.27 1.27)
				)
			)
		)
		(duplicate_pad_numbers_are_jumpers no)
		(fp_line
			(start -0.7874 -0.4064)
			(end 0.7874 -0.4064)
			(stroke
				(width 0.1524)
				(type default)
			)
			(layer "F.SilkS")
		)
		(fp_line
			(start -0.7874 0.4064)
			(end -0.7874 -0.4064)
			(stroke
				(width 0.1524)
				(type default)
			)
			(layer "F.SilkS")
		)
		(fp_line
			(start 0.7874 -0.4064)
			(end 0.7874 0.4064)
			(stroke
				(width 0.1524)
				(type default)
			)
			(layer "F.SilkS")
		)
		(fp_line
			(start 0.7874 0.4064)
			(end -0.7874 0.4064)
			(stroke
				(width 0.1524)
				(type default)
			)
			(layer "F.SilkS")
		)
		(fp_line
			(start -0.67945 -0.305054)
			(end -0.12065 -0.305054)
			(stroke
				(width 0.1)
				(type default)
			)
			(layer "F.Fab")
		)
		(fp_line
			(start -0.67945 0.3048)
			(end -0.67945 -0.305054)
			(stroke
				(width 0.1)
				(type default)
			)
			(layer "F.Fab")
		)
		(fp_line
			(start -0.12065 -0.305054)
			(end -0.12065 -0.2794)
			(stroke
				(width 0.1)
				(type default)
			)
			(layer "F.Fab")
		)
		(fp_line
			(start -0.12065 -0.2794)
			(end 0.12065 -0.2794)
			(stroke
				(width 0.1)
				(type default)
			)
			(layer "F.Fab")
		)
		(fp_line
			(start -0.12065 0.2794)
			(end -0.12065 0.3048)
			(stroke
				(width 0.1)
				(type default)
			)
			(layer "F.Fab")
		)
		(fp_line
			(start -0.12065 0.3048)
			(end -0.67945 0.3048)
			(stroke
				(width 0.1)
				(type default)
			)
			(layer "F.Fab")
		)
		(fp_line
			(start 0.120396 0.2794)
			(end -0.12065 0.2794)
			(stroke
				(width 0.1)
				(type default)
			)
			(layer "F.Fab")
		)
		(fp_line
			(start 0.120396 0.3048)
			(end 0.120396 0.2794)
			(stroke
				(width 0.1)
				(type default)
			)
			(layer "F.Fab")
		)
		(fp_line
			(start 0.12065 -0.3048)
			(end 0.67945 -0.3048)
			(stroke
				(width 0.1)
				(type default)
			)
			(layer "F.Fab")
		)
		(fp_line
			(start 0.12065 -0.2794)
			(end 0.12065 -0.3048)
			(stroke
				(width 0.1)
				(type default)
			)
			(layer "F.Fab")
		)
		(fp_line
			(start 0.67945 -0.3048)
			(end 0.67945 0.3048)
			(stroke
				(width 0.1)
				(type default)
			)
			(layer "F.Fab")
		)
		(fp_line
			(start 0.67945 0.3048)
			(end 0.120396 0.3048)
			(stroke
				(width 0.1)
				(type default)
			)
			(layer "F.Fab")
		)
		(pad "1" smd circle
			(at -0.40005 0)
			(size 0 0)
			(layers "F.Cu" "F.Mask" "F.Paste")
			(net "JTAG_SCM_PLD_R_TCK")
		)
		(pad "2" smd circle
			(at 0.40005 0)
			(size 0 0)
			(layers "F.Cu" "F.Mask" "F.Paste")
			(net "JTAG_SCM_PLD_TCK")
		)
	)
)
